(kicad_pcb
	(version 20260206)
	(generator "pcbnew")
	(generator_version "10.0")
	(general
		(thickness 1.6)
		(legacy_teardrops no)
	)
	(paper "A4")
	(title_block
		(title "Bryce Canyon_IOM_M2_16342-2_OCP.brd")
		(comment 1 "Bryce Canyon / footprints 537-544 of 1146")
	)
	(layers
		(0 "F.Cu" signal "TOP")
		(4 "In1.Cu" signal "L2GND")
		(6 "In2.Cu" signal "L3")
		(8 "In3.Cu" signal "L4VCC")
		(10 "In4.Cu" signal "L5VCC")
		(12 "In5.Cu" signal "L6")
		(14 "In6.Cu" signal "L7GND")
		(2 "B.Cu" signal "BOTTOM")
		(9 "F.Adhes" user "F.Adhesive")
		(11 "B.Adhes" user "B.Adhesive")
		(13 "F.Paste" user "Package Geometry/Pastemask Top")
		(15 "B.Paste" user "Package Geometry/Pastemask Bottom")
		(5 "F.SilkS" user "Ref Des/Silkscreen Top")
		(7 "B.SilkS" user "Ref Des/Silkscreen Bottom")
		(1 "F.Mask" user "Board Geometry/Soldermask Top")
		(3 "B.Mask" user "Board Geometry/Soldermask Bottom")
		(17 "Dwgs.User" user "User.Drawings")
		(19 "Cmts.User" user "User.Comments")
		(21 "Eco1.User" user "User.Eco1")
		(23 "Eco2.User" user "User.Eco2")
		(25 "Edge.Cuts" user "Board Geometry/Outline")
		(27 "Margin" user)
		(31 "F.CrtYd" user "Package Geometry/Place Bound Top")
		(29 "B.CrtYd" user "Package Geometry/Place Bound Bottom")
		(35 "F.Fab" user "Ref Des/Assembly Top")
		(33 "B.Fab" user "Ref Des/Assembly Bottom")
	)
	(footprint ""
		(layer "F.Cu")
		(at 98.501708 -176.332642 -90)
		(property "Reference" "R736"
			(at 0 0 270)
			(layer "F.SilkS")
			(hide yes)
			(effects
				(font
					(size 1.27 1.27)
				)
			)
		)
		(property "Value" "0R2J-2-GP"
			(at 0.064008 -3.993896 270)
			(unlocked yes)
			(layer "F.Fab")
			(hide yes)
			(effects
				(font
					(size 1.016 1.016)
					(thickness 0.1524)
				)
			)
		)
		(property "Device Type" "R402H16"
			(at 0.064008 -5.517896 270)
			(unlocked yes)
			(layer "F.Fab")
			(hide yes)
			(effects
				(font
					(size 1.016 1.016)
					(thickness 0.1524)
				)
			)
		)
		(duplicate_pad_numbers_are_jumpers no)
		(fp_line
			(start -0.508 -0.9398)
			(end -0.508 0.9398)
			(stroke
				(width 0.1524)
				(type default)
			)
			(layer "F.SilkS")
		)
		(fp_line
			(start 0.508 -0.9398)
			(end -0.508 -0.9398)
			(stroke
				(width 0.1524)
				(type default)
			)
			(layer "F.SilkS")
		)
		(fp_rect
			(start -0.508 0.9398)
			(end 0.508 -0.9398)
			(stroke
				(width 0)
				(type default)
			)
			(fill no)
			(layer "F.CrtYd")
		)
		(fp_rect
			(start -0.508 0.9398)
			(end 0.508 -0.9398)
			(stroke
				(width 0)
				(type default)
			)
			(fill no)
			(layer "F.Fab")
		)
		(pad "1" smd custom
			(at 0 -0.4445 270)
			(size 0.1397 0.1397)
			(layers "F.Cu" "F.Mask" "F.Paste")
			(net "PWRGD_P3V3_STBY_N")
			(options
				(clearance outline)
				(anchor circle)
			)
			(primitives
				(gr_poly
					(pts
						(arc
							(start -0.1778 -0.2794)
							(mid -0.249642 -0.249642)
							(end -0.2794 -0.1778)
						)
						(arc
							(start -0.2794 0.1778)
							(mid -0.249642 0.249642)
							(end -0.1778 0.2794)
						)
						(arc
							(start 0.1778 0.2794)
							(mid 0.249642 0.249642)
							(end 0.2794 0.1778)
						)
						(arc
							(start 0.2794 -0.1778)
							(mid 0.249642 -0.249642)
							(end 0.1778 -0.2794)
						)
					)
					(width 0)
					(fill yes)
				)
			)
		)
		(pad "2" smd custom
			(at 0 0.4445 270)
			(size 0.1397 0.1397)
			(layers "F.Cu" "F.Mask" "F.Paste")
			(net "PWRGD_P3V3_STBY_N_R2")
			(options
				(clearance outline)
				(anchor circle)
			)
			(primitives
				(gr_poly
					(pts
						(arc
							(start -0.1778 -0.2794)
							(mid -0.249642 -0.249642)
							(end -0.2794 -0.1778)
						)
						(arc
							(start -0.2794 0.1778)
							(mid -0.249642 0.249642)
							(end -0.1778 0.2794)
						)
						(arc
							(start 0.1778 0.2794)
							(mid 0.249642 0.249642)
							(end 0.2794 0.1778)
						)
						(arc
							(start 0.2794 -0.1778)
							(mid 0.249642 -0.249642)
							(end 0.1778 -0.2794)
						)
					)
					(width 0)
					(fill yes)
				)
			)
		)
	)
	(footprint ""
		(layer "F.Cu")
		(at 72.4408 -134.8994 -90)
		(property "Reference" "C40"
			(at 0 0 270)
			(layer "F.SilkS")
			(hide yes)
			(effects
				(font
					(size 1.27 1.27)
				)
			)
		)
		(property "Value" "SCD1U16V2KX-3GP"
			(at 1.1811 -2.7051 270)
			(unlocked yes)
			(layer "F.Fab")
			(hide yes)
			(effects
				(font
					(size 1.016 1.016)
					(thickness 0.1524)
				)
			)
		)
		(property "Device Type" "C402H22"
			(at 1.1811 -4.2291 270)
			(unlocked yes)
			(layer "F.Fab")
			(hide yes)
			(effects
				(font
					(size 1.016 1.016)
					(thickness 0.1524)
				)
			)
		)
		(duplicate_pad_numbers_are_jumpers no)
		(fp_rect
			(start -0.4318 0.9525)
			(end 0.4318 -0.9525)
			(stroke
				(width 0)
				(type default)
			)
			(fill no)
			(layer "F.CrtYd")
		)
		(fp_rect
			(start -0.4318 0.9525)
			(end 0.4318 -0.9525)
			(stroke
				(width 0)
				(type default)
			)
			(fill no)
			(layer "F.Fab")
		)
		(pad "1" smd custom
			(at 0 -0.4445 270)
			(size 0.1524 0.1524)
			(layers "F.Cu" "F.Mask" "F.Paste")
			(net "D_FLIP_CLR#")
			(options
				(clearance outline)
				(anchor circle)
			)
			(primitives
				(gr_poly
					(pts
						(arc
							(start 0.3048 -0.2032)
							(mid 0.275042 -0.275042)
							(end 0.2032 -0.3048)
						)
						(arc
							(start -0.2032 -0.3048)
							(mid -0.275042 -0.275042)
							(end -0.3048 -0.2032)
						)
						(arc
							(start -0.3048 0.2032)
							(mid -0.275042 0.275042)
							(end -0.2032 0.3048)
						)
						(arc
							(start 0.2032 0.3048)
							(mid 0.275042 0.275042)
							(end 0.3048 0.2032)
						)
					)
					(width 0)
					(fill yes)
				)
			)
		)
		(pad "2" smd custom
			(at 0 0.4445 270)
			(size 0.1524 0.1524)
			(layers "F.Cu" "F.Mask" "F.Paste")
			(net "GND")
			(options
				(clearance outline)
				(anchor circle)
			)
			(primitives
				(gr_poly
					(pts
						(arc
							(start 0.3048 -0.2032)
							(mid 0.275042 -0.275042)
							(end 0.2032 -0.3048)
						)
						(arc
							(start -0.2032 -0.3048)
							(mid -0.275042 -0.275042)
							(end -0.3048 -0.2032)
						)
						(arc
							(start -0.3048 0.2032)
							(mid -0.275042 0.275042)
							(end -0.2032 0.3048)
						)
						(arc
							(start 0.2032 0.3048)
							(mid 0.275042 0.275042)
							(end 0.3048 0.2032)
						)
					)
					(width 0)
					(fill yes)
				)
			)
		)
	)
	(footprint ""
		(layer "F.Cu")
		(at 228.249988 -18.469356)
		(property "Reference" "C166"
			(at 0 0 0)
			(layer "F.SilkS")
			(hide yes)
			(effects
				(font
					(size 1.27 1.27)
				)
			)
		)
		(property "Value" "SC10U16V5KX-7-GP-U"
			(at -0.0762 -6.1214 0)
			(unlocked yes)
			(layer "F.Fab")
			(hide yes)
			(effects
				(font
					(size 1.016 1.016)
					(thickness 0.1524)
				)
			)
		)
		(property "Device Type" "C805H58"
			(at -0.0762 -8.1534 0)
			(unlocked yes)
			(layer "F.Fab")
			(hide yes)
			(effects
				(font
					(size 1.016 1.016)
					(thickness 0.1524)
				)
			)
		)
		(duplicate_pad_numbers_are_jumpers no)
		(fp_line
			(start 0.635 0)
			(end -0.635 0)
			(stroke
				(width 0.508)
				(type default)
			)
			(layer "F.SilkS")
		)
		(fp_rect
			(start -0.9652 1.778)
			(end 0.9652 -1.778)
			(stroke
				(width 0)
				(type default)
			)
			(fill no)
			(layer "F.CrtYd")
		)
		(fp_poly
			(pts
				(xy -0.9652 -1.778) (xy 0.9652 -1.778) (xy 0.9652 1.778) (xy -0.9652 1.778)
			)
			(stroke
				(width 0)
				(type default)
			)
			(fill no)
			(layer "F.Fab")
		)
		(pad "1" smd rect
			(at 0 -0.9652)
			(size 1.397 1.143)
			(layers "F.Cu" "F.Mask" "F.Paste")
			(net "P5V_STBY")
		)
		(pad "2" smd rect
			(at 0 0.9652)
			(size 1.397 1.143)
			(layers "F.Cu" "F.Mask" "F.Paste")
			(net "GND")
		)
	)
	(footprint ""
		(layer "F.Cu")
		(at 41.1226 -159.4612)
		(property "Reference" "TP188"
			(at 0 0 0)
			(layer "F.SilkS")
			(hide yes)
			(effects
				(font
					(size 1.27 1.27)
				)
			)
		)
		(property "Value" "TPAD28-2-GP"
			(at -0.0127 -1.6637 0)
			(unlocked yes)
			(layer "F.Fab")
			(hide yes)
			(effects
				(font
					(size 1.016 1.016)
					(thickness 0.1524)
				)
			)
		)
		(property "Device Type" "TPAD28"
			(at -0.0127 -3.1877 0)
			(unlocked yes)
			(layer "F.Fab")
			(hide yes)
			(effects
				(font
					(size 1.016 1.016)
					(thickness 0.1524)
				)
			)
		)
		(duplicate_pad_numbers_are_jumpers no)
		(fp_poly
			(pts
				(arc
					(start 0.3556 0)
					(mid -0.3556 0)
					(end 0.3556 0)
				)
			)
			(stroke
				(width 0)
				(type default)
			)
			(fill no)
			(layer "F.CrtYd")
		)
		(fp_poly
			(pts
				(arc
					(start 0.6096 0)
					(mid -0.6096 0)
					(end 0.6096 0)
				)
			)
			(stroke
				(width 0)
				(type default)
			)
			(fill no)
			(layer "F.Fab")
		)
		(pad "1" smd circle
			(at 0 0)
			(size 0.7112 0.7112)
			(layers "F.Cu" "F.Mask" "F.Paste")
			(net "TP_BMC_GPIOL2")
		)
	)
	(footprint ""
		(layer "F.Cu")
		(at 61.468 -149.8092 90)
		(property "Reference" "R338"
			(at 0 0 90)
			(layer "F.SilkS")
			(hide yes)
			(effects
				(font
					(size 1.27 1.27)
				)
			)
		)
		(property "Value" "8K2R2J-3-GP"
			(at 0.064008 -3.993896 90)
			(unlocked yes)
			(layer "F.Fab")
			(hide yes)
			(effects
				(font
					(size 1.016 1.016)
					(thickness 0.1524)
				)
			)
		)
		(property "Device Type" "R402H16"
			(at 0.064008 -5.517896 90)
			(unlocked yes)
			(layer "F.Fab")
			(hide yes)
			(effects
				(font
					(size 1.016 1.016)
					(thickness 0.1524)
				)
			)
		)
		(duplicate_pad_numbers_are_jumpers no)
		(fp_line
			(start 0.508 -0.9398)
			(end -0.508 -0.9398)
			(stroke
				(width 0.1524)
				(type default)
			)
			(layer "F.SilkS")
		)
		(fp_line
			(start -0.508 -0.9398)
			(end -0.508 0.9398)
			(stroke
				(width 0.1524)
				(type default)
			)
			(layer "F.SilkS")
		)
		(fp_rect
			(start -0.508 0.9398)
			(end 0.508 -0.9398)
			(stroke
				(width 0)
				(type default)
			)
			(fill no)
			(layer "F.CrtYd")
		)
		(fp_rect
			(start -0.508 0.9398)
			(end 0.508 -0.9398)
			(stroke
				(width 0)
				(type default)
			)
			(fill no)
			(layer "F.Fab")
		)
		(pad "1" smd custom
			(at 0 -0.4445 90)
			(size 0.1397 0.1397)
			(layers "F.Cu" "F.Mask" "F.Paste")
			(net "PD_USB2AVRES")
			(options
				(clearance outline)
				(anchor circle)
			)
			(primitives
				(gr_poly
					(pts
						(arc
							(start -0.1778 -0.2794)
							(mid -0.249642 -0.249642)
							(end -0.2794 -0.1778)
						)
						(arc
							(start -0.2794 0.1778)
							(mid -0.249642 0.249642)
							(end -0.1778 0.2794)
						)
						(arc
							(start 0.1778 0.2794)
							(mid 0.249642 0.249642)
							(end 0.2794 0.1778)
						)
						(arc
							(start 0.2794 -0.1778)
							(mid 0.249642 -0.249642)
							(end 0.1778 -0.2794)
						)
					)
					(width 0)
					(fill yes)
				)
			)
		)
		(pad "2" smd custom
			(at 0 0.4445 90)
			(size 0.1397 0.1397)
			(layers "F.Cu" "F.Mask" "F.Paste")
			(net "GND")
			(options
				(clearance outline)
				(anchor circle)
			)
			(primitives
				(gr_poly
					(pts
						(arc
							(start -0.1778 -0.2794)
							(mid -0.249642 -0.249642)
							(end -0.2794 -0.1778)
						)
						(arc
							(start -0.2794 0.1778)
							(mid -0.249642 0.249642)
							(end -0.1778 0.2794)
						)
						(arc
							(start 0.1778 0.2794)
							(mid 0.249642 0.249642)
							(end 0.2794 0.1778)
						)
						(arc
							(start 0.2794 -0.1778)
							(mid 0.249642 -0.249642)
							(end 0.1778 -0.2794)
						)
					)
					(width 0)
					(fill yes)
				)
			)
		)
	)
	(footprint ""
		(layer "F.Cu")
		(at 209.931 -140.843 -135)
		(property "Reference" "VIA50"
			(at 0 0 225)
			(layer "F.SilkS")
			(hide yes)
			(effects
				(font
					(size 1.27 1.27)
				)
			)
		)
		(property "Value" "85OHM-8L-1D6MM-L16L18-GP"
			(at 4.064105 0.609655 225)
			(unlocked yes)
			(layer "F.Fab")
			(hide yes)
			(effects
				(font
					(size 1.016 1.016)
					(thickness 0.1524)
				)
			)
		)
		(property "Device Type" "VIA-PCIE-4P-368076"
			(at 4.064105 -0.914474 225)
			(unlocked yes)
			(layer "F.Fab")
			(hide yes)
			(effects
				(font
					(size 1.016 1.016)
					(thickness 0.1524)
				)
			)
		)
		(duplicate_pad_numbers_are_jumpers no)
		(fp_poly
			(pts
				(xy -1.841491 -0.381057) (xy 1.841509 -0.381058) (xy 1.841508 0.380942) (xy -1.841491 0.380942)
			)
			(stroke
				(width 0)
				(type default)
			)
			(fill no)
			(layer "F.CrtYd")
		)
		(fp_poly
			(pts
				(xy -1.841491 -0.381057) (xy 1.841509 -0.381058) (xy 1.841508 0.380942) (xy -1.841491 0.380942)
			)
			(stroke
				(width 0)
				(type default)
			)
			(fill no)
			(layer "F.Fab")
		)
		(pad "1" thru_hole circle
			(at -1.460499 0 225)
			(size 0.508 0.508)
			(drill 0.254)
			(layers "*.Cu" "*.Mask")
			(remove_unused_layers no)
			(net "GND")
			(clearance 0.127)
			(thermal_gap 0.127)
		)
		(pad "2" thru_hole circle
			(at -0.4445 0 225)
			(size 0.508 0.508)
			(drill 0.254)
			(layers "*.Cu" "*.Mask")
			(remove_unused_layers no)
			(net "PCIE_COMP_TO_IOM_8_DP")
			(clearance 0.127)
			(thermal_gap 0.127)
		)
		(pad "3" thru_hole circle
			(at 0.4445 0 225)
			(size 0.508 0.508)
			(drill 0.254)
			(layers "*.Cu" "*.Mask")
			(remove_unused_layers no)
			(net "PCIE_COMP_TO_IOM_8_DN")
			(clearance 0.127)
			(thermal_gap 0.127)
		)
		(pad "4" thru_hole circle
			(at 1.460499 0 225)
			(size 0.508 0.508)
			(drill 0.254)
			(layers "*.Cu" "*.Mask")
			(remove_unused_layers no)
			(net "GND")
			(clearance 0.127)
			(thermal_gap 0.127)
		)
	)
	(footprint ""
		(layer "F.Cu")
		(at 61.4426 -148.7678 -90)
		(property "Reference" "R164"
			(at 0 0 270)
			(layer "F.SilkS")
			(hide yes)
			(effects
				(font
					(size 1.27 1.27)
				)
			)
		)
		(property "Value" "0R2J-2-GP"
			(at 0.064008 -3.993896 270)
			(unlocked yes)
			(layer "F.Fab")
			(hide yes)
			(effects
				(font
					(size 1.016 1.016)
					(thickness 0.1524)
				)
			)
		)
		(property "Device Type" "R402H16"
			(at 0.064008 -5.517896 270)
			(unlocked yes)
			(layer "F.Fab")
			(hide yes)
			(effects
				(font
					(size 1.016 1.016)
					(thickness 0.1524)
				)
			)
		)
		(duplicate_pad_numbers_are_jumpers no)
		(fp_line
			(start -0.508 -0.9398)
			(end -0.508 0.9398)
			(stroke
				(width 0.1524)
				(type default)
			)
			(layer "F.SilkS")
		)
		(fp_line
			(start 0.508 -0.9398)
			(end -0.508 -0.9398)
			(stroke
				(width 0.1524)
				(type default)
			)
			(layer "F.SilkS")
		)
		(fp_rect
			(start -0.508 0.9398)
			(end 0.508 -0.9398)
			(stroke
				(width 0)
				(type default)
			)
			(fill no)
			(layer "F.CrtYd")
		)
		(fp_rect
			(start -0.508 0.9398)
			(end 0.508 -0.9398)
			(stroke
				(width 0)
				(type default)
			)
			(fill no)
			(layer "F.Fab")
		)
		(pad "1" smd custom
			(at 0 -0.4445 270)
			(size 0.1397 0.1397)
			(layers "F.Cu" "F.Mask" "F.Paste")
			(net "I2C_BMC_COMP_SCL_OUT")
			(options
				(clearance outline)
				(anchor circle)
			)
			(primitives
				(gr_poly
					(pts
						(arc
							(start -0.1778 -0.2794)
							(mid -0.249642 -0.249642)
							(end -0.2794 -0.1778)
						)
						(arc
							(start -0.2794 0.1778)
							(mid -0.249642 0.249642)
							(end -0.1778 0.2794)
						)
						(arc
							(start 0.1778 0.2794)
							(mid 0.249642 0.249642)
							(end 0.2794 0.1778)
						)
						(arc
							(start 0.2794 -0.1778)
							(mid 0.249642 -0.249642)
							(end 0.1778 -0.2794)
						)
					)
					(width 0)
					(fill yes)
				)
			)
		)
		(pad "2" smd custom
			(at 0 0.4445 270)
			(size 0.1397 0.1397)
			(layers "F.Cu" "F.Mask" "F.Paste")
			(net "BMC_SMB4_CLK")
			(options
				(clearance outline)
				(anchor circle)
			)
			(primitives
				(gr_poly
					(pts
						(arc
							(start -0.1778 -0.2794)
							(mid -0.249642 -0.249642)
							(end -0.2794 -0.1778)
						)
						(arc
							(start -0.2794 0.1778)
							(mid -0.249642 0.249642)
							(end -0.1778 0.2794)
						)
						(arc
							(start 0.1778 0.2794)
							(mid 0.249642 0.249642)
							(end 0.2794 0.1778)
						)
						(arc
							(start 0.2794 -0.1778)
							(mid 0.249642 -0.249642)
							(end 0.1778 -0.2794)
						)
					)
					(width 0)
					(fill yes)
				)
			)
		)
	)
	(footprint ""
		(layer "F.Cu")
		(at 21.851112 -175.625506)
		(property "Reference" "R532"
			(at 0 0 0)
			(layer "F.SilkS")
			(hide yes)
			(effects
				(font
					(size 1.27 1.27)
				)
			)
		)
		(property "Value" "10KR2F-2-GP"
			(at 0.064008 -3.993896 0)
			(unlocked yes)
			(layer "F.Fab")
			(hide yes)
			(effects
				(font
					(size 1.016 1.016)
					(thickness 0.1524)
				)
			)
		)
		(property "Device Type" "R402H16"
			(at 0.064008 -5.517896 0)
			(unlocked yes)
			(layer "F.Fab")
			(hide yes)
			(effects
				(font
					(size 1.016 1.016)
					(thickness 0.1524)
				)
			)
		)
		(duplicate_pad_numbers_are_jumpers no)
		(fp_line
			(start -0.508 -0.9398)
			(end -0.508 0.9398)
			(stroke
				(width 0.1524)
				(type default)
			)
			(layer "F.SilkS")
		)
		(fp_line
			(start 0.508 -0.9398)
			(end -0.508 -0.9398)
			(stroke
				(width 0.1524)
				(type default)
			)
			(layer "F.SilkS")
		)
		(fp_rect
			(start -0.508 0.9398)
			(end 0.508 -0.9398)
			(stroke
				(width 0)
				(type default)
			)
			(fill no)
			(layer "F.CrtYd")
		)
		(fp_rect
			(start -0.508 0.9398)
			(end 0.508 -0.9398)
			(stroke
				(width 0)
				(type default)
			)
			(fill no)
			(layer "F.Fab")
		)
		(pad "1" smd custom
			(at 0 -0.4445)
			(size 0.1397 0.1397)
			(layers "F.Cu" "F.Mask" "F.Paste")
			(net "P3V3_STBY")
			(options
				(clearance outline)
				(anchor circle)
			)
			(primitives
				(gr_poly
					(pts
						(arc
							(start -0.1778 -0.2794)
							(mid -0.249642 -0.249642)
							(end -0.2794 -0.1778)
						)
						(arc
							(start -0.2794 0.1778)
							(mid -0.249642 0.249642)
							(end -0.1778 0.2794)
						)
						(arc
							(start 0.1778 0.2794)
							(mid 0.249642 0.249642)
							(end 0.2794 0.1778)
						)
						(arc
							(start 0.2794 -0.1778)
							(mid 0.249642 -0.249642)
							(end 0.1778 -0.2794)
						)
					)
					(width 0)
					(fill yes)
				)
			)
		)
		(pad "2" smd custom
			(at 0 0.4445)
			(size 0.1397 0.1397)
			(layers "F.Cu" "F.Mask" "F.Paste")
			(net "PWRGD_P1V2_STBY")
			(options
				(clearance outline)
				(anchor circle)
			)
			(primitives
				(gr_poly
					(pts
						(arc
							(start -0.1778 -0.2794)
							(mid -0.249642 -0.249642)
							(end -0.2794 -0.1778)
						)
						(arc
							(start -0.2794 0.1778)
							(mid -0.249642 0.249642)
							(end -0.1778 0.2794)
						)
						(arc
							(start 0.1778 0.2794)
							(mid 0.249642 0.249642)
							(end 0.2794 0.1778)
						)
						(arc
							(start 0.2794 -0.1778)
							(mid 0.249642 -0.249642)
							(end 0.1778 -0.2794)
						)
					)
					(width 0)
					(fill yes)
				)
			)
		)
	)
)
